# S9S_MB_2U (Grand Teton) — schematic netlist excerpt (pin names and nets, part order shuffled) for the footprints in the layout excerpt that follows; sources: Cadence DE-HDL packaged netlist, KiCad conversion of 03242023_DA0F0TMBIJ0_F0T_Motherboard_J_brd_V01_OCP.brd

R378  Q_RES  1K 1% EMPTY  pkg 0402LF  page 198 : A = P3V3_AUX ; B = FM_ADR_MODE1
R3889  Q_RES  49.9 1% CHIP  pkg 0402LF  page 96 : A = I3C_SPD_DDREFGH_CPU0_LVC1_SCL_6 ; B = I3C_SPD_DDREFGH_CPU0_LVC1_SCL

(kicad_pcb
	(version 20260206)
	(generator "pcbnew")
	(generator_version "10.0")
	(general
		(thickness 1.6)
		(legacy_teardrops no)
	)
	(paper "A4")
	(title_block
		(title "03242023_DA0F0TMBIJ0_F0T_Motherboard_J_brd_V01_OCP.brd")
		(comment 1 "Grand Teton / footprints 5247-5248 of 6105")
	)
	(layers
		(0 "F.Cu" signal "TOP")
		(4 "In1.Cu" signal "GND")
		(6 "In2.Cu" signal "IN1")
		(8 "In3.Cu" signal "GND1")
		(10 "In4.Cu" signal "IN2")
		(12 "In5.Cu" signal "GND2")
		(14 "In6.Cu" signal "IN3")
		(16 "In7.Cu" signal "GND3")
		(18 "In8.Cu" signal "VCC")
		(20 "In9.Cu" signal "VCC1")
		(22 "In10.Cu" signal "GND4")
		(24 "In11.Cu" signal "IN4")
		(26 "In12.Cu" signal "GND5")
		(28 "In13.Cu" signal "IN5")
		(30 "In14.Cu" signal "GND6")
		(32 "In15.Cu" signal "IN6")
		(34 "In16.Cu" signal "GND7")
		(2 "B.Cu" signal "BOTTOM")
		(9 "F.Adhes" user "F.Adhesive")
		(11 "B.Adhes" user "B.Adhesive")
		(13 "F.Paste" user "Package Geometry/Pastemask Top")
		(15 "B.Paste" user "Package Geometry/Pastemask Bottom")
		(5 "F.SilkS" user "Ref Des/Silkscreen Top")
		(7 "B.SilkS" user "Ref Des/Silkscreen Bottom")
		(1 "F.Mask" user "Board Geometry/Soldermask Top")
		(3 "B.Mask" user "Board Geometry/Soldermask Bottom")
		(17 "Dwgs.User" user "User.Drawings")
		(19 "Cmts.User" user "User.Comments")
		(21 "Eco1.User" user "User.Eco1")
		(23 "Eco2.User" user "User.Eco2")
		(25 "Edge.Cuts" user "Board Geometry/Outline")
		(27 "Margin" user)
		(31 "F.CrtYd" user "Package Geometry/Place Bound Top")
		(29 "B.CrtYd" user "Package Geometry/Place Bound Bottom")
		(35 "F.Fab" user "Ref Des/Assembly Top")
		(33 "B.Fab" user "Ref Des/Assembly Bottom")
	)
	(footprint ""
		(layer "B.Cu")
		(at 461.35544 -314.772294 90)
		(property "Reference" "R3889"
			(at 0 0 90)
			(layer "B.SilkS")
			(hide yes)
			(effects
				(font
					(size 1.27 1.27)
				)
				(justify mirror)
			)
		)
		(property "Value" ""
			(at 0 0 90)
			(layer "B.Fab")
			(effects
				(font
					(size 1.27 1.27)
				)
				(justify mirror)
			)
		)
		(duplicate_pad_numbers_are_jumpers no)
		(fp_line
			(start 0.7874 -0.4064)
			(end -0.7874 -0.4064)
			(stroke
				(width 0.1524)
				(type default)
			)
			(layer "B.SilkS")
		)
		(fp_line
			(start -0.7874 -0.4064)
			(end -0.7874 0.4064)
			(stroke
				(width 0.1524)
				(type default)
			)
			(layer "B.SilkS")
		)
		(fp_line
			(start 0.7874 0.4064)
			(end 0.7874 -0.4064)
			(stroke
				(width 0.1524)
				(type default)
			)
			(layer "B.SilkS")
		)
		(fp_line
			(start -0.7874 0.4064)
			(end 0.7874 0.4064)
			(stroke
				(width 0.1524)
				(type default)
			)
			(layer "B.SilkS")
		)
		(fp_line
			(start 0.67945 -0.305054)
			(end 0.12065 -0.305054)
			(stroke
				(width 0.1)
				(type default)
			)
			(layer "B.Fab")
		)
		(fp_line
			(start 0.12065 -0.305054)
			(end 0.12065 -0.2794)
			(stroke
				(width 0.1)
				(type default)
			)
			(layer "B.Fab")
		)
		(fp_line
			(start -0.12065 -0.3048)
			(end -0.67945 -0.3048)
			(stroke
				(width 0.1)
				(type default)
			)
			(layer "B.Fab")
		)
		(fp_line
			(start -0.67945 -0.3048)
			(end -0.67945 0.3048)
			(stroke
				(width 0.1)
				(type default)
			)
			(layer "B.Fab")
		)
		(fp_line
			(start 0.12065 -0.2794)
			(end -0.12065 -0.2794)
			(stroke
				(width 0.1)
				(type default)
			)
			(layer "B.Fab")
		)
		(fp_line
			(start -0.12065 -0.2794)
			(end -0.12065 -0.3048)
			(stroke
				(width 0.1)
				(type default)
			)
			(layer "B.Fab")
		)
		(fp_line
			(start 0.12065 0.2794)
			(end 0.12065 0.3048)
			(stroke
				(width 0.1)
				(type default)
			)
			(layer "B.Fab")
		)
		(fp_line
			(start -0.120396 0.2794)
			(end 0.12065 0.2794)
			(stroke
				(width 0.1)
				(type default)
			)
			(layer "B.Fab")
		)
		(fp_line
			(start 0.67945 0.3048)
			(end 0.67945 -0.305054)
			(stroke
				(width 0.1)
				(type default)
			)
			(layer "B.Fab")
		)
		(fp_line
			(start 0.12065 0.3048)
			(end 0.67945 0.3048)
			(stroke
				(width 0.1)
				(type default)
			)
			(layer "B.Fab")
		)
		(fp_line
			(start -0.120396 0.3048)
			(end -0.120396 0.2794)
			(stroke
				(width 0.1)
				(type default)
			)
			(layer "B.Fab")
		)
		(fp_line
			(start -0.67945 0.3048)
			(end -0.120396 0.3048)
			(stroke
				(width 0.1)
				(type default)
			)
			(layer "B.Fab")
		)
		(pad "1" smd circle
			(at 0.40005 0 270)
			(size 0 0)
			(layers "B.Cu" "B.Mask" "B.Paste")
			(net "I3C_SPD_DDREFGH_CPU0_LVC1_SCL_6")
		)
		(pad "2" smd circle
			(at -0.40005 0 270)
			(size 0 0)
			(layers "B.Cu" "B.Mask" "B.Paste")
			(net "I3C_SPD_DDREFGH_CPU0_LVC1_SCL")
		)
	)
	(footprint ""
		(layer "B.Cu")
		(at 309.25389 -30.734508)
		(property "Reference" "R378"
			(at 0 0 0)
			(layer "B.SilkS")
			(hide yes)
			(effects
				(font
					(size 1.27 1.27)
				)
				(justify mirror)
			)
		)
		(property "Value" ""
			(at 0 0 0)
			(layer "B.Fab")
			(effects
				(font
					(size 1.27 1.27)
				)
				(justify mirror)
			)
		)
		(duplicate_pad_numbers_are_jumpers no)
		(fp_line
			(start -0.7874 -0.4064)
			(end -0.7874 0.4064)
			(stroke
				(width 0.1524)
				(type default)
			)
			(layer "B.SilkS")
		)
		(fp_line
			(start -0.7874 0.4064)
			(end 0.7874 0.4064)
			(stroke
				(width 0.1524)
				(type default)
			)
			(layer "B.SilkS")
		)
		(fp_line
			(start 0.7874 -0.4064)
			(end -0.7874 -0.4064)
			(stroke
				(width 0.1524)
				(type default)
			)
			(layer "B.SilkS")
		)
		(fp_line
			(start 0.7874 0.4064)
			(end 0.7874 -0.4064)
			(stroke
				(width 0.1524)
				(type default)
			)
			(layer "B.SilkS")
		)
		(fp_line
			(start -0.67945 -0.3048)
			(end -0.67945 0.3048)
			(stroke
				(width 0.1)
				(type default)
			)
			(layer "B.Fab")
		)
		(fp_line
			(start -0.67945 0.3048)
			(end -0.120396 0.3048)
			(stroke
				(width 0.1)
				(type default)
			)
			(layer "B.Fab")
		)
		(fp_line
			(start -0.12065 -0.3048)
			(end -0.67945 -0.3048)
			(stroke
				(width 0.1)
				(type default)
			)
			(layer "B.Fab")
		)
		(fp_line
			(start -0.12065 -0.2794)
			(end -0.12065 -0.3048)
			(stroke
				(width 0.1)
				(type default)
			)
			(layer "B.Fab")
		)
		(fp_line
			(start -0.120396 0.2794)
			(end 0.12065 0.2794)
			(stroke
				(width 0.1)
				(type default)
			)
			(layer "B.Fab")
		)
		(fp_line
			(start -0.120396 0.3048)
			(end -0.120396 0.2794)
			(stroke
				(width 0.1)
				(type default)
			)
			(layer "B.Fab")
		)
		(fp_line
			(start 0.12065 -0.305054)
			(end 0.12065 -0.2794)
			(stroke
				(width 0.1)
				(type default)
			)
			(layer "B.Fab")
		)
		(fp_line
			(start 0.12065 -0.2794)
			(end -0.12065 -0.2794)
			(stroke
				(width 0.1)
				(type default)
			)
			(layer "B.Fab")
		)
		(fp_line
			(start 0.12065 0.2794)
			(end 0.12065 0.3048)
			(stroke
				(width 0.1)
				(type default)
			)
			(layer "B.Fab")
		)
		(fp_line
			(start 0.12065 0.3048)
			(end 0.67945 0.3048)
			(stroke
				(width 0.1)
				(type default)
			)
			(layer "B.Fab")
		)
		(fp_line
			(start 0.67945 -0.305054)
			(end 0.12065 -0.305054)
			(stroke
				(width 0.1)
				(type default)
			)
			(layer "B.Fab")
		)
		(fp_line
			(start 0.67945 0.3048)
			(end 0.67945 -0.305054)
			(stroke
				(width 0.1)
				(type default)
			)
			(layer "B.Fab")
		)
		(pad "1" smd circle
			(at 0.40005 0 180)
			(size 0 0)
			(layers "B.Cu" "B.Mask" "B.Paste")
			(net "P3V3_AUX")
		)
		(pad "2" smd circle
			(at -0.40005 0 180)
			(size 0 0)
			(layers "B.Cu" "B.Mask" "B.Paste")
			(net "FM_ADR_MODE1")
		)
	)
)
